# T6G (Grand Teton) — schematic netlist excerpt (pin names and nets, part order shuffled) for the footprints in the layout excerpt that follows; sources: Cadence DE-HDL packaged netlist, KiCad conversion of 04192023_DAF0TMB3IC0_F0TG_MB_C_brd_V02_OCP.brd

H99  HOLE  EMPTY  pkg TH  page 230 : \1\ = GND
PC202  Q_CAP  560PF 50V 10% EMPTY  pkg C0402  page 218 : A = SW_PVDDCR_CPU1_P1_SW2 ; B = SW_PVDDCR_CPU1_P1_SW2_RC
C752  Q_CAP_DIFFBUS  DIFF BUS_0.22UF 6.3V 20% X6S  pkg C0201  page 66 : \1\ = P5E_CPU1_P2_TX_C_DN<10> ; \2\ = P5E_CPU1_P2_TX_DN<10>
R793  Q_RES  4.7K 5% CHIP  pkg 0201LF  page 331 : A = P1V8_CPU1_RT_1D ; B = MODE_RT_CPU1_P1

(kicad_pcb
	(version 20260206)
	(generator "pcbnew")
	(generator_version "10.0")
	(general
		(thickness 1.6)
		(legacy_teardrops no)
	)
	(paper "A4")
	(title_block
		(title "04192023_DAF0TMB3IC0_F0TG_MB_C_brd_V02_OCP.brd")
		(comment 1 "Grand Teton / footprints 4714-4717 of 8354")
	)
	(layers
		(0 "F.Cu" signal "TOP")
		(4 "In1.Cu" signal "GND")
		(6 "In2.Cu" signal "IN1")
		(8 "In3.Cu" signal "GND1")
		(10 "In4.Cu" signal "IN2")
		(12 "In5.Cu" signal "GND2")
		(14 "In6.Cu" signal "IN3")
		(16 "In7.Cu" signal "GND3")
		(18 "In8.Cu" signal "VCC")
		(20 "In9.Cu" signal "VCC1")
		(22 "In10.Cu" signal "GND4")
		(24 "In11.Cu" signal "IN4")
		(26 "In12.Cu" signal "GND5")
		(28 "In13.Cu" signal "IN5")
		(30 "In14.Cu" signal "GND6")
		(32 "In15.Cu" signal "IN6")
		(34 "In16.Cu" signal "GND7")
		(2 "B.Cu" signal "BOTTOM")
		(9 "F.Adhes" user "F.Adhesive")
		(11 "B.Adhes" user "B.Adhesive")
		(13 "F.Paste" user "Package Geometry/Pastemask Top")
		(15 "B.Paste" user "Package Geometry/Pastemask Bottom")
		(5 "F.SilkS" user "Ref Des/Silkscreen Top")
		(7 "B.SilkS" user "Ref Des/Silkscreen Bottom")
		(1 "F.Mask" user "Board Geometry/Soldermask Top")
		(3 "B.Mask" user "Board Geometry/Soldermask Bottom")
		(17 "Dwgs.User" user "User.Drawings")
		(19 "Cmts.User" user "User.Comments")
		(21 "Eco1.User" user "User.Eco1")
		(23 "Eco2.User" user "User.Eco2")
		(25 "Edge.Cuts" user "Board Geometry/Outline")
		(27 "Margin" user)
		(31 "F.CrtYd" user "Package Geometry/Place Bound Top")
		(29 "B.CrtYd" user "Package Geometry/Place Bound Bottom")
		(35 "F.Fab" user "Ref Des/Assembly Top")
		(33 "B.Fab" user "Ref Des/Assembly Bottom")
	)
	(footprint ""
		(layer "F.Cu")
		(at 75.070716 -331.988668 180)
		(property "Reference" "PC202"
			(at 0 0 180)
			(layer "F.SilkS")
			(hide yes)
			(effects
				(font
					(size 1.27 1.27)
				)
			)
		)
		(property "Value" ""
			(at 0 0 180)
			(layer "F.Fab")
			(effects
				(font
					(size 1.27 1.27)
				)
			)
		)
		(duplicate_pad_numbers_are_jumpers no)
		(fp_line
			(start 0.7874 0.4064)
			(end -0.7874 0.4064)
			(stroke
				(width 0.1524)
				(type default)
			)
			(layer "F.SilkS")
		)
		(fp_line
			(start 0.7874 -0.4064)
			(end 0.7874 0.4064)
			(stroke
				(width 0.1524)
				(type default)
			)
			(layer "F.SilkS")
		)
		(fp_line
			(start -0.7874 0.4064)
			(end -0.7874 -0.4064)
			(stroke
				(width 0.1524)
				(type default)
			)
			(layer "F.SilkS")
		)
		(fp_line
			(start -0.7874 -0.4064)
			(end 0.7874 -0.4064)
			(stroke
				(width 0.1524)
				(type default)
			)
			(layer "F.SilkS")
		)
		(fp_line
			(start 0.67945 0.3048)
			(end 0.120396 0.3048)
			(stroke
				(width 0.1)
				(type default)
			)
			(layer "F.Fab")
		)
		(fp_line
			(start 0.67945 -0.3048)
			(end 0.67945 0.3048)
			(stroke
				(width 0.1)
				(type default)
			)
			(layer "F.Fab")
		)
		(fp_line
			(start 0.12065 -0.2794)
			(end 0.12065 -0.3048)
			(stroke
				(width 0.1)
				(type default)
			)
			(layer "F.Fab")
		)
		(fp_line
			(start 0.12065 -0.3048)
			(end 0.67945 -0.3048)
			(stroke
				(width 0.1)
				(type default)
			)
			(layer "F.Fab")
		)
		(fp_line
			(start 0.120396 0.3048)
			(end 0.120396 0.2794)
			(stroke
				(width 0.1)
				(type default)
			)
			(layer "F.Fab")
		)
		(fp_line
			(start 0.120396 0.2794)
			(end -0.12065 0.2794)
			(stroke
				(width 0.1)
				(type default)
			)
			(layer "F.Fab")
		)
		(fp_line
			(start -0.12065 0.3048)
			(end -0.67945 0.3048)
			(stroke
				(width 0.1)
				(type default)
			)
			(layer "F.Fab")
		)
		(fp_line
			(start -0.12065 0.2794)
			(end -0.12065 0.3048)
			(stroke
				(width 0.1)
				(type default)
			)
			(layer "F.Fab")
		)
		(fp_line
			(start -0.12065 -0.2794)
			(end 0.12065 -0.2794)
			(stroke
				(width 0.1)
				(type default)
			)
			(layer "F.Fab")
		)
		(fp_line
			(start -0.12065 -0.305054)
			(end -0.12065 -0.2794)
			(stroke
				(width 0.1)
				(type default)
			)
			(layer "F.Fab")
		)
		(fp_line
			(start -0.67945 0.3048)
			(end -0.67945 -0.305054)
			(stroke
				(width 0.1)
				(type default)
			)
			(layer "F.Fab")
		)
		(fp_line
			(start -0.67945 -0.305054)
			(end -0.12065 -0.305054)
			(stroke
				(width 0.1)
				(type default)
			)
			(layer "F.Fab")
		)
		(pad "1" smd circle
			(at -0.40005 0 180)
			(size 0 0)
			(layers "F.Cu" "F.Mask" "F.Paste")
			(net "SW_PVDDCR_CPU1_P1_SW2")
		)
		(pad "2" smd circle
			(at 0.40005 0 180)
			(size 0 0)
			(layers "F.Cu" "F.Mask" "F.Paste")
			(net "SW_PVDDCR_CPU1_P1_SW2_RC")
		)
	)
	(footprint ""
		(layer "F.Cu")
		(at 236.650022 -192.499996)
		(property "Reference" "H99"
			(at -3.30454 -6.229604 0)
			(unlocked yes)
			(layer "F.SilkS")
			(effects
				(font
					(size 0.7874 0.5842)
					(thickness 0.1524)
				)
				(justify left)
			)
		)
		(property "Value" ""
			(at 0 0 0)
			(layer "F.Fab")
			(effects
				(font
					(size 1.27 1.27)
				)
			)
		)
		(duplicate_pad_numbers_are_jumpers no)
		(pad "1" thru_hole circle
			(at 0 0)
			(size 10.0076 10.0076)
			(drill 5.6134)
			(layers "*.Cu" "*.Mask")
			(remove_unused_layers no)
			(net "GND")
			(clearance -1.9431)
		)
	)
	(footprint ""
		(layer "F.Cu")
		(at 162.251644 -375.49963 -90)
		(property "Reference" "C752"
			(at 0 0 270)
			(layer "F.SilkS")
			(hide yes)
			(effects
				(font
					(size 1.27 1.27)
				)
			)
		)
		(property "Value" ""
			(at 0 0 270)
			(layer "F.Fab")
			(effects
				(font
					(size 1.27 1.27)
				)
			)
		)
		(duplicate_pad_numbers_are_jumpers no)
		(fp_line
			(start -0.299974 0.150114)
			(end -0.299974 -0.150114)
			(stroke
				(width 0.1)
				(type default)
			)
			(layer "F.Fab")
		)
		(fp_line
			(start 0.299974 0.150114)
			(end -0.299974 0.150114)
			(stroke
				(width 0.1)
				(type default)
			)
			(layer "F.Fab")
		)
		(fp_line
			(start -0.299974 -0.150114)
			(end 0.299974 -0.150114)
			(stroke
				(width 0.1)
				(type default)
			)
			(layer "F.Fab")
		)
		(fp_line
			(start 0.299974 -0.150114)
			(end 0.299974 0.150114)
			(stroke
				(width 0.1)
				(type default)
			)
			(layer "F.Fab")
		)
		(pad "1" smd rect
			(at -0.2667 0 270)
			(size 0.3048 0.381)
			(layers "F.Cu" "F.Mask" "F.Paste")
			(net "P5E_CPU1_P2_TX_C_DN<10>")
		)
		(pad "2" smd rect
			(at 0.2667 0 270)
			(size 0.3048 0.381)
			(layers "F.Cu" "F.Mask" "F.Paste")
			(net "P5E_CPU1_P2_TX_DN<10>")
		)
	)
	(footprint ""
		(layer "F.Cu")
		(at 78.028546 -395.436852 -90)
		(property "Reference" "R793"
			(at 0 0 270)
			(layer "F.SilkS")
			(hide yes)
			(effects
				(font
					(size 1.27 1.27)
				)
			)
		)
		(property "Value" ""
			(at 0 0 270)
			(layer "F.Fab")
			(effects
				(font
					(size 1.27 1.27)
				)
			)
		)
		(duplicate_pad_numbers_are_jumpers no)
		(fp_line
			(start -0.32512 0.175006)
			(end -0.32512 -0.175006)
			(stroke
				(width 0.1)
				(type default)
			)
			(layer "F.Fab")
		)
		(fp_line
			(start 0.32512 0.175006)
			(end -0.32512 0.175006)
			(stroke
				(width 0.1)
				(type default)
			)
			(layer "F.Fab")
		)
		(fp_line
			(start -0.32512 -0.175006)
			(end 0.32512 -0.175006)
			(stroke
				(width 0.1)
				(type default)
			)
			(layer "F.Fab")
		)
		(fp_line
			(start 0.32512 -0.175006)
			(end 0.32512 0.175006)
			(stroke
				(width 0.1)
				(type default)
			)
			(layer "F.Fab")
		)
		(pad "1" smd rect
			(at -0.2667 0 270)
			(size 0.3048 0.381)
			(layers "F.Cu" "F.Mask" "F.Paste")
			(net "P1V8_CPU1_RT_1D")
		)
		(pad "2" smd rect
			(at 0.2667 0 90)
			(size 0.3048 0.381)
			(layers "F.Cu" "F.Mask" "F.Paste")
			(net "MODE_RT_CPU1_P1")
		)
	)
)
